(kicad_pcb
	(version 20260206)
	(generator "pcbnew")
	(generator_version "10.0")
	(general
		(thickness 1.6)
		(legacy_teardrops no)
	)
	(paper "A4")
	(title_block
		(title "01162023_DA0F0TEBIF0_F0T_Expander_BD_F_brd_V02_OCP.brd")
		(comment 1 "Grand Teton / footprints 2142-2147 of 9728")
	)
	(layers
		(0 "F.Cu" signal "TOP")
		(4 "In1.Cu" signal "GND")
		(6 "In2.Cu" signal "VCC")
		(8 "In3.Cu" signal "VCC1")
		(10 "In4.Cu" signal "GND1")
		(12 "In5.Cu" signal "IN1")
		(14 "In6.Cu" signal "GND2")
		(16 "In7.Cu" signal "IN2")
		(18 "In8.Cu" signal "GND3")
		(20 "In9.Cu" signal "IN3")
		(22 "In10.Cu" signal "GND4")
		(24 "In11.Cu" signal "IN4")
		(26 "In12.Cu" signal "GND5")
		(28 "In13.Cu" signal "IN5")
		(30 "In14.Cu" signal "GND6")
		(32 "In15.Cu" signal "IN6")
		(34 "In16.Cu" signal "GND7")
		(2 "B.Cu" signal "BOTTOM")
		(9 "F.Adhes" user "F.Adhesive")
		(11 "B.Adhes" user "B.Adhesive")
		(13 "F.Paste" user "Package Geometry/Pastemask Top")
		(15 "B.Paste" user "Package Geometry/Pastemask Bottom")
		(5 "F.SilkS" user "Ref Des/Silkscreen Top")
		(7 "B.SilkS" user "Ref Des/Silkscreen Bottom")
		(1 "F.Mask" user "Board Geometry/Soldermask Top")
		(3 "B.Mask" user "Board Geometry/Soldermask Bottom")
		(17 "Dwgs.User" user "User.Drawings")
		(19 "Cmts.User" user "User.Comments")
		(21 "Eco1.User" user "User.Eco1")
		(23 "Eco2.User" user "User.Eco2")
		(25 "Edge.Cuts" user "Board Geometry/Outline")
		(27 "Margin" user)
		(31 "F.CrtYd" user "Package Geometry/Place Bound Top")
		(29 "B.CrtYd" user "Package Geometry/Place Bound Bottom")
		(35 "F.Fab" user "Ref Des/Assembly Top")
		(33 "B.Fab" user "Ref Des/Assembly Bottom")
	)
	(footprint ""
		(layer "F.Cu")
		(at 268.506448 -87.251286)
		(property "Reference" "R1057"
			(at 0 0 0)
			(layer "F.SilkS")
			(hide yes)
			(effects
				(font
					(size 1.27 1.27)
				)
			)
		)
		(property "Value" ""
			(at 0 0 0)
			(layer "F.Fab")
			(effects
				(font
					(size 1.27 1.27)
				)
			)
		)
		(duplicate_pad_numbers_are_jumpers no)
		(fp_line
			(start -0.7874 -0.4064)
			(end 0.7874 -0.4064)
			(stroke
				(width 0.1524)
				(type default)
			)
			(layer "F.SilkS")
		)
		(fp_line
			(start -0.7874 0.4064)
			(end -0.7874 -0.4064)
			(stroke
				(width 0.1524)
				(type default)
			)
			(layer "F.SilkS")
		)
		(fp_line
			(start 0.7874 -0.4064)
			(end 0.7874 0.4064)
			(stroke
				(width 0.1524)
				(type default)
			)
			(layer "F.SilkS")
		)
		(fp_line
			(start 0.7874 0.4064)
			(end -0.7874 0.4064)
			(stroke
				(width 0.1524)
				(type default)
			)
			(layer "F.SilkS")
		)
		(fp_line
			(start -0.67945 -0.305054)
			(end -0.12065 -0.305054)
			(stroke
				(width 0.1)
				(type default)
			)
			(layer "F.Fab")
		)
		(fp_line
			(start -0.67945 0.3048)
			(end -0.67945 -0.305054)
			(stroke
				(width 0.1)
				(type default)
			)
			(layer "F.Fab")
		)
		(fp_line
			(start -0.12065 -0.305054)
			(end -0.12065 -0.2794)
			(stroke
				(width 0.1)
				(type default)
			)
			(layer "F.Fab")
		)
		(fp_line
			(start -0.12065 -0.2794)
			(end 0.12065 -0.2794)
			(stroke
				(width 0.1)
				(type default)
			)
			(layer "F.Fab")
		)
		(fp_line
			(start -0.12065 0.2794)
			(end -0.12065 0.3048)
			(stroke
				(width 0.1)
				(type default)
			)
			(layer "F.Fab")
		)
		(fp_line
			(start -0.12065 0.3048)
			(end -0.67945 0.3048)
			(stroke
				(width 0.1)
				(type default)
			)
			(layer "F.Fab")
		)
		(fp_line
			(start 0.120396 0.2794)
			(end -0.12065 0.2794)
			(stroke
				(width 0.1)
				(type default)
			)
			(layer "F.Fab")
		)
		(fp_line
			(start 0.120396 0.3048)
			(end 0.120396 0.2794)
			(stroke
				(width 0.1)
				(type default)
			)
			(layer "F.Fab")
		)
		(fp_line
			(start 0.12065 -0.3048)
			(end 0.67945 -0.3048)
			(stroke
				(width 0.1)
				(type default)
			)
			(layer "F.Fab")
		)
		(fp_line
			(start 0.12065 -0.2794)
			(end 0.12065 -0.3048)
			(stroke
				(width 0.1)
				(type default)
			)
			(layer "F.Fab")
		)
		(fp_line
			(start 0.67945 -0.3048)
			(end 0.67945 0.3048)
			(stroke
				(width 0.1)
				(type default)
			)
			(layer "F.Fab")
		)
		(fp_line
			(start 0.67945 0.3048)
			(end 0.120396 0.3048)
			(stroke
				(width 0.1)
				(type default)
			)
			(layer "F.Fab")
		)
		(pad "1" smd circle
			(at -0.40005 0)
			(size 0 0)
			(layers "F.Cu" "F.Mask" "F.Paste")
			(net "CLK_BUFFER_DB2000QL_OE0_N")
		)
		(pad "2" smd circle
			(at 0.40005 0)
			(size 0 0)
			(layers "F.Cu" "F.Mask" "F.Paste")
			(net "P3V3")
		)
	)
	(footprint ""
		(layer "F.Cu")
		(at 375.230136 -300.406308 -90)
		(property "Reference" "C3539"
			(at 0 0 270)
			(layer "F.SilkS")
			(hide yes)
			(effects
				(font
					(size 1.27 1.27)
				)
			)
		)
		(property "Value" ""
			(at 0 0 270)
			(layer "F.Fab")
			(effects
				(font
					(size 1.27 1.27)
				)
			)
		)
		(duplicate_pad_numbers_are_jumpers no)
		(fp_line
			(start -1.2954 0.5842)
			(end -1.2954 -0.5842)
			(stroke
				(width 0.1524)
				(type default)
			)
			(layer "F.SilkS")
		)
		(fp_line
			(start 1.2954 0.5842)
			(end -1.2954 0.5842)
			(stroke
				(width 0.1524)
				(type default)
			)
			(layer "F.SilkS")
		)
		(fp_line
			(start -1.2954 -0.5842)
			(end 1.2954 -0.5842)
			(stroke
				(width 0.1524)
				(type default)
			)
			(layer "F.SilkS")
		)
		(fp_line
			(start 1.2954 -0.5842)
			(end 1.2954 0.5842)
			(stroke
				(width 0.1524)
				(type default)
			)
			(layer "F.SilkS")
		)
		(fp_line
			(start -0.8636 0.4572)
			(end -0.8636 0.4064)
			(stroke
				(width 0.1)
				(type default)
			)
			(layer "F.Fab")
		)
		(fp_line
			(start 0.8636 0.4572)
			(end -0.8636 0.4572)
			(stroke
				(width 0.1)
				(type default)
			)
			(layer "F.Fab")
		)
		(fp_line
			(start -1.1938 0.4064)
			(end -1.1938 -0.4064)
			(stroke
				(width 0.1)
				(type default)
			)
			(layer "F.Fab")
		)
		(fp_line
			(start -0.8636 0.4064)
			(end -1.1938 0.4064)
			(stroke
				(width 0.1)
				(type default)
			)
			(layer "F.Fab")
		)
		(fp_line
			(start 0.8636 0.4064)
			(end 0.8636 0.4572)
			(stroke
				(width 0.1)
				(type default)
			)
			(layer "F.Fab")
		)
		(fp_line
			(start 1.1938 0.4064)
			(end 0.8636 0.4064)
			(stroke
				(width 0.1)
				(type default)
			)
			(layer "F.Fab")
		)
		(fp_line
			(start -1.1938 -0.4064)
			(end -0.8636 -0.4064)
			(stroke
				(width 0.1)
				(type default)
			)
			(layer "F.Fab")
		)
		(fp_line
			(start -0.8636 -0.4064)
			(end -0.8636 -0.4572)
			(stroke
				(width 0.1)
				(type default)
			)
			(layer "F.Fab")
		)
		(fp_line
			(start 0.8636 -0.4064)
			(end 1.1938 -0.4064)
			(stroke
				(width 0.1)
				(type default)
			)
			(layer "F.Fab")
		)
		(fp_line
			(start 1.1938 -0.4064)
			(end 1.1938 0.4064)
			(stroke
				(width 0.1)
				(type default)
			)
			(layer "F.Fab")
		)
		(fp_line
			(start -0.8636 -0.4572)
			(end 0.8636 -0.4572)
			(stroke
				(width 0.1)
				(type default)
			)
			(layer "F.Fab")
		)
		(fp_line
			(start 0.8636 -0.4572)
			(end 0.8636 -0.4064)
			(stroke
				(width 0.1)
				(type default)
			)
			(layer "F.Fab")
		)
		(pad "1" smd rect
			(at -0.7366 0 180)
			(size 0.7112 0.8128)
			(layers "F.Cu" "F.Mask" "F.Paste")
			(net "P1V8_PLL0_PEX3")
		)
		(pad "2" smd rect
			(at 0.7366 0 180)
			(size 0.7112 0.8128)
			(layers "F.Cu" "F.Mask" "F.Paste")
			(net "GND")
		)
	)
	(footprint ""
		(layer "F.Cu")
		(at 460.354934 -284.375606)
		(property "Reference" "PC279"
			(at 0 0 0)
			(layer "F.SilkS")
			(hide yes)
			(effects
				(font
					(size 1.27 1.27)
				)
			)
		)
		(property "Value" ""
			(at 0 0 0)
			(layer "F.Fab")
			(effects
				(font
					(size 1.27 1.27)
				)
			)
		)
		(duplicate_pad_numbers_are_jumpers no)
		(fp_line
			(start -2.750058 -1.988058)
			(end -2.750058 -0.9398)
			(stroke
				(width 0.1524)
				(type default)
			)
			(layer "F.SilkS")
		)
		(fp_line
			(start -2.750058 0.9398)
			(end -2.750058 1.988058)
			(stroke
				(width 0.1524)
				(type default)
			)
			(layer "F.SilkS")
		)
		(fp_line
			(start -2.750058 1.988058)
			(end -1.988058 2.750058)
			(stroke
				(width 0.1524)
				(type default)
			)
			(layer "F.SilkS")
		)
		(fp_line
			(start -1.988058 -2.750058)
			(end -2.750058 -1.988058)
			(stroke
				(width 0.1524)
				(type default)
			)
			(layer "F.SilkS")
		)
		(fp_line
			(start -1.988058 2.750058)
			(end 2.750058 2.750058)
			(stroke
				(width 0.1524)
				(type default)
			)
			(layer "F.SilkS")
		)
		(fp_line
			(start 2.750058 -2.750058)
			(end -1.988058 -2.750058)
			(stroke
				(width 0.1524)
				(type default)
			)
			(layer "F.SilkS")
		)
		(fp_line
			(start 2.750058 -0.9398)
			(end 2.750058 -2.750058)
			(stroke
				(width 0.1524)
				(type default)
			)
			(layer "F.SilkS")
		)
		(fp_line
			(start 2.750058 2.750058)
			(end 2.750058 0.9398)
			(stroke
				(width 0.1524)
				(type default)
			)
			(layer "F.SilkS")
		)
		(fp_line
			(start -2.750058 -2.750058)
			(end -2.750058 2.750058)
			(stroke
				(width 0.1)
				(type default)
			)
			(layer "F.Fab")
		)
		(fp_line
			(start -2.750058 2.750058)
			(end 2.750058 2.750058)
			(stroke
				(width 0.1)
				(type default)
			)
			(layer "F.Fab")
		)
		(fp_line
			(start 2.750058 -2.750058)
			(end -2.750058 -2.750058)
			(stroke
				(width 0.1)
				(type default)
			)
			(layer "F.Fab")
		)
		(fp_line
			(start 2.750058 2.750058)
			(end 2.750058 -2.750058)
			(stroke
				(width 0.1)
				(type default)
			)
			(layer "F.Fab")
		)
		(pad "1" smd rect
			(at -2.199894 0 90)
			(size 1.6002 3.0226)
			(layers "F.Cu" "F.Mask" "F.Paste")
			(net "P1V25_PEX3_R")
		)
		(pad "2" smd rect
			(at 2.199894 0 90)
			(size 1.6002 3.0226)
			(layers "F.Cu" "F.Mask" "F.Paste")
			(net "GND")
		)
	)
	(footprint ""
		(layer "F.Cu")
		(at 414.371282 -203.962508 -90)
		(property "Reference" "R6439"
			(at 0 0 270)
			(layer "F.SilkS")
			(hide yes)
			(effects
				(font
					(size 1.27 1.27)
				)
			)
		)
		(property "Value" ""
			(at 0 0 270)
			(layer "F.Fab")
			(effects
				(font
					(size 1.27 1.27)
				)
			)
		)
		(duplicate_pad_numbers_are_jumpers no)
		(fp_line
			(start -0.7874 0.4064)
			(end -0.7874 -0.4064)
			(stroke
				(width 0.1524)
				(type default)
			)
			(layer "F.SilkS")
		)
		(fp_line
			(start 0.7874 0.4064)
			(end -0.7874 0.4064)
			(stroke
				(width 0.1524)
				(type default)
			)
			(layer "F.SilkS")
		)
		(fp_line
			(start -0.7874 -0.4064)
			(end 0.7874 -0.4064)
			(stroke
				(width 0.1524)
				(type default)
			)
			(layer "F.SilkS")
		)
		(fp_line
			(start 0.7874 -0.4064)
			(end 0.7874 0.4064)
			(stroke
				(width 0.1524)
				(type default)
			)
			(layer "F.SilkS")
		)
		(fp_line
			(start -0.67945 0.3048)
			(end -0.67945 -0.305054)
			(stroke
				(width 0.1)
				(type default)
			)
			(layer "F.Fab")
		)
		(fp_line
			(start -0.12065 0.3048)
			(end -0.67945 0.3048)
			(stroke
				(width 0.1)
				(type default)
			)
			(layer "F.Fab")
		)
		(fp_line
			(start 0.120396 0.3048)
			(end 0.120396 0.2794)
			(stroke
				(width 0.1)
				(type default)
			)
			(layer "F.Fab")
		)
		(fp_line
			(start 0.67945 0.3048)
			(end 0.120396 0.3048)
			(stroke
				(width 0.1)
				(type default)
			)
			(layer "F.Fab")
		)
		(fp_line
			(start -0.12065 0.2794)
			(end -0.12065 0.3048)
			(stroke
				(width 0.1)
				(type default)
			)
			(layer "F.Fab")
		)
		(fp_line
			(start 0.120396 0.2794)
			(end -0.12065 0.2794)
			(stroke
				(width 0.1)
				(type default)
			)
			(layer "F.Fab")
		)
		(fp_line
			(start -0.12065 -0.2794)
			(end 0.12065 -0.2794)
			(stroke
				(width 0.1)
				(type default)
			)
			(layer "F.Fab")
		)
		(fp_line
			(start 0.12065 -0.2794)
			(end 0.12065 -0.3048)
			(stroke
				(width 0.1)
				(type default)
			)
			(layer "F.Fab")
		)
		(fp_line
			(start 0.12065 -0.3048)
			(end 0.67945 -0.3048)
			(stroke
				(width 0.1)
				(type default)
			)
			(layer "F.Fab")
		)
		(fp_line
			(start 0.67945 -0.3048)
			(end 0.67945 0.3048)
			(stroke
				(width 0.1)
				(type default)
			)
			(layer "F.Fab")
		)
		(fp_line
			(start -0.67945 -0.305054)
			(end -0.12065 -0.305054)
			(stroke
				(width 0.1)
				(type default)
			)
			(layer "F.Fab")
		)
		(fp_line
			(start -0.12065 -0.305054)
			(end -0.12065 -0.2794)
			(stroke
				(width 0.1)
				(type default)
			)
			(layer "F.Fab")
		)
		(pad "1" smd circle
			(at -0.40005 0 270)
			(size 0 0)
			(layers "F.Cu" "F.Mask" "F.Paste")
			(net "FPGA_PEX2_MODE_SEL2_D_N")
		)
		(pad "2" smd circle
			(at 0.40005 0 270)
			(size 0 0)
			(layers "F.Cu" "F.Mask" "F.Paste")
			(net "P3V3_AUX")
		)
	)
	(footprint ""
		(layer "F.Cu")
		(at 244.555264 -113.517426 90)
		(property "Reference" "R6036"
			(at 0 0 90)
			(layer "F.SilkS")
			(hide yes)
			(effects
				(font
					(size 1.27 1.27)
				)
			)
		)
		(property "Value" ""
			(at 0 0 90)
			(layer "F.Fab")
			(effects
				(font
					(size 1.27 1.27)
				)
			)
		)
		(duplicate_pad_numbers_are_jumpers no)
		(fp_line
			(start 0.7874 -0.4064)
			(end 0.7874 0.4064)
			(stroke
				(width 0.1524)
				(type default)
			)
			(layer "F.SilkS")
		)
		(fp_line
			(start -0.7874 -0.4064)
			(end 0.7874 -0.4064)
			(stroke
				(width 0.1524)
				(type default)
			)
			(layer "F.SilkS")
		)
		(fp_line
			(start 0.7874 0.4064)
			(end -0.7874 0.4064)
			(stroke
				(width 0.1524)
				(type default)
			)
			(layer "F.SilkS")
		)
		(fp_line
			(start -0.7874 0.4064)
			(end -0.7874 -0.4064)
			(stroke
				(width 0.1524)
				(type default)
			)
			(layer "F.SilkS")
		)
		(fp_line
			(start -0.12065 -0.305054)
			(end -0.12065 -0.2794)
			(stroke
				(width 0.1)
				(type default)
			)
			(layer "F.Fab")
		)
		(fp_line
			(start -0.67945 -0.305054)
			(end -0.12065 -0.305054)
			(stroke
				(width 0.1)
				(type default)
			)
			(layer "F.Fab")
		)
		(fp_line
			(start 0.67945 -0.3048)
			(end 0.67945 0.3048)
			(stroke
				(width 0.1)
				(type default)
			)
			(layer "F.Fab")
		)
		(fp_line
			(start 0.12065 -0.3048)
			(end 0.67945 -0.3048)
			(stroke
				(width 0.1)
				(type default)
			)
			(layer "F.Fab")
		)
		(fp_line
			(start 0.12065 -0.2794)
			(end 0.12065 -0.3048)
			(stroke
				(width 0.1)
				(type default)
			)
			(layer "F.Fab")
		)
		(fp_line
			(start -0.12065 -0.2794)
			(end 0.12065 -0.2794)
			(stroke
				(width 0.1)
				(type default)
			)
			(layer "F.Fab")
		)
		(fp_line
			(start 0.120396 0.2794)
			(end -0.12065 0.2794)
			(stroke
				(width 0.1)
				(type default)
			)
			(layer "F.Fab")
		)
		(fp_line
			(start -0.12065 0.2794)
			(end -0.12065 0.3048)
			(stroke
				(width 0.1)
				(type default)
			)
			(layer "F.Fab")
		)
		(fp_line
			(start 0.67945 0.3048)
			(end 0.120396 0.3048)
			(stroke
				(width 0.1)
				(type default)
			)
			(layer "F.Fab")
		)
		(fp_line
			(start 0.120396 0.3048)
			(end 0.120396 0.2794)
			(stroke
				(width 0.1)
				(type default)
			)
			(layer "F.Fab")
		)
		(fp_line
			(start -0.12065 0.3048)
			(end -0.67945 0.3048)
			(stroke
				(width 0.1)
				(type default)
			)
			(layer "F.Fab")
		)
		(fp_line
			(start -0.67945 0.3048)
			(end -0.67945 -0.305054)
			(stroke
				(width 0.1)
				(type default)
			)
			(layer "F.Fab")
		)
		(pad "1" smd circle
			(at -0.40005 0 90)
			(size 0 0)
			(layers "F.Cu" "F.Mask" "F.Paste")
			(net "P5V_AUX")
		)
		(pad "2" smd circle
			(at 0.40005 0 90)
			(size 0 0)
			(layers "F.Cu" "F.Mask" "F.Paste")
			(net "P3V3_NIC4_PG_G2")
		)
	)
	(footprint ""
		(layer "F.Cu")
		(at 196.810376 -411.72638 90)
		(property "Reference" "C4479"
			(at 0 0 90)
			(layer "F.SilkS")
			(hide yes)
			(effects
				(font
					(size 1.27 1.27)
				)
			)
		)
		(property "Value" ""
			(at 0 0 90)
			(layer "F.Fab")
			(effects
				(font
					(size 1.27 1.27)
				)
			)
		)
		(duplicate_pad_numbers_are_jumpers no)
		(fp_line
			(start 0.7874 -0.4064)
			(end 0.7874 0.4064)
			(stroke
				(width 0.1524)
				(type default)
			)
			(layer "F.SilkS")
		)
		(fp_line
			(start -0.7874 -0.4064)
			(end 0.7874 -0.4064)
			(stroke
				(width 0.1524)
				(type default)
			)
			(layer "F.SilkS")
		)
		(fp_line
			(start 0.7874 0.4064)
			(end -0.7874 0.4064)
			(stroke
				(width 0.1524)
				(type default)
			)
			(layer "F.SilkS")
		)
		(fp_line
			(start -0.7874 0.4064)
			(end -0.7874 -0.4064)
			(stroke
				(width 0.1524)
				(type default)
			)
			(layer "F.SilkS")
		)
		(fp_line
			(start -0.12065 -0.305054)
			(end -0.12065 -0.2794)
			(stroke
				(width 0.1)
				(type default)
			)
			(layer "F.Fab")
		)
		(fp_line
			(start -0.67945 -0.305054)
			(end -0.12065 -0.305054)
			(stroke
				(width 0.1)
				(type default)
			)
			(layer "F.Fab")
		)
		(fp_line
			(start 0.67945 -0.3048)
			(end 0.67945 0.3048)
			(stroke
				(width 0.1)
				(type default)
			)
			(layer "F.Fab")
		)
		(fp_line
			(start 0.12065 -0.3048)
			(end 0.67945 -0.3048)
			(stroke
				(width 0.1)
				(type default)
			)
			(layer "F.Fab")
		)
		(fp_line
			(start 0.12065 -0.2794)
			(end 0.12065 -0.3048)
			(stroke
				(width 0.1)
				(type default)
			)
			(layer "F.Fab")
		)
		(fp_line
			(start -0.12065 -0.2794)
			(end 0.12065 -0.2794)
			(stroke
				(width 0.1)
				(type default)
			)
			(layer "F.Fab")
		)
		(fp_line
			(start 0.120396 0.2794)
			(end -0.12065 0.2794)
			(stroke
				(width 0.1)
				(type default)
			)
			(layer "F.Fab")
		)
		(fp_line
			(start -0.12065 0.2794)
			(end -0.12065 0.3048)
			(stroke
				(width 0.1)
				(type default)
			)
			(layer "F.Fab")
		)
		(fp_line
			(start 0.67945 0.3048)
			(end 0.120396 0.3048)
			(stroke
				(width 0.1)
				(type default)
			)
			(layer "F.Fab")
		)
		(fp_line
			(start 0.120396 0.3048)
			(end 0.120396 0.2794)
			(stroke
				(width 0.1)
				(type default)
			)
			(layer "F.Fab")
		)
		(fp_line
			(start -0.12065 0.3048)
			(end -0.67945 0.3048)
			(stroke
				(width 0.1)
				(type default)
			)
			(layer "F.Fab")
		)
		(fp_line
			(start -0.67945 0.3048)
			(end -0.67945 -0.305054)
			(stroke
				(width 0.1)
				(type default)
			)
			(layer "F.Fab")
		)
		(pad "1" smd circle
			(at -0.40005 0 90)
			(size 0 0)
			(layers "F.Cu" "F.Mask" "F.Paste")
			(net "P12V_AUX")
		)
		(pad "2" smd circle
			(at 0.40005 0 90)
			(size 0 0)
			(layers "F.Cu" "F.Mask" "F.Paste")
			(net "GND")
		)
	)
)
